# S9S_MB_2U (Grand Teton) — schematic netlist excerpt (pin names and nets, part order shuffled) for the footprints in the layout excerpt that follows; sources: Cadence DE-HDL packaged netlist, KiCad conversion of 03242023_DA0F0TMBIJ0_F0T_Motherboard_J_brd_V01_OCP.brd

C684  Q_CAP_DIFFBUS  DIFF BUS_0.22UF 6.3V 20% X6S  pkg C0201  page 177 : \1\ = P5E_CPU1_PE4_TX_C_DN<12> ; \2\ = P5E_CPU1_PE4_TX_DN<12>
R3799  Q_RES  100K 1% EMPTY  pkg 0402LF  page 156 : A = P3V3_AUX ; B = P12V_OCP_FAULT_1
R4449  Q_RES  10K 1% EMPTY  pkg 0402LF  page 196 : A = USB_HUB_2_PSELF ; B = GND

(kicad_pcb
	(version 20260206)
	(generator "pcbnew")
	(generator_version "10.0")
	(general
		(thickness 1.6)
		(legacy_teardrops no)
	)
	(paper "A4")
	(title_block
		(title "03242023_DA0F0TMBIJ0_F0T_Motherboard_J_brd_V01_OCP.brd")
		(comment 1 "Grand Teton / footprints 2955-2957 of 6105")
	)
	(layers
		(0 "F.Cu" signal "TOP")
		(4 "In1.Cu" signal "GND")
		(6 "In2.Cu" signal "IN1")
		(8 "In3.Cu" signal "GND1")
		(10 "In4.Cu" signal "IN2")
		(12 "In5.Cu" signal "GND2")
		(14 "In6.Cu" signal "IN3")
		(16 "In7.Cu" signal "GND3")
		(18 "In8.Cu" signal "VCC")
		(20 "In9.Cu" signal "VCC1")
		(22 "In10.Cu" signal "GND4")
		(24 "In11.Cu" signal "IN4")
		(26 "In12.Cu" signal "GND5")
		(28 "In13.Cu" signal "IN5")
		(30 "In14.Cu" signal "GND6")
		(32 "In15.Cu" signal "IN6")
		(34 "In16.Cu" signal "GND7")
		(2 "B.Cu" signal "BOTTOM")
		(9 "F.Adhes" user "F.Adhesive")
		(11 "B.Adhes" user "B.Adhesive")
		(13 "F.Paste" user "Package Geometry/Pastemask Top")
		(15 "B.Paste" user "Package Geometry/Pastemask Bottom")
		(5 "F.SilkS" user "Ref Des/Silkscreen Top")
		(7 "B.SilkS" user "Ref Des/Silkscreen Bottom")
		(1 "F.Mask" user "Board Geometry/Soldermask Top")
		(3 "B.Mask" user "Board Geometry/Soldermask Bottom")
		(17 "Dwgs.User" user "User.Drawings")
		(19 "Cmts.User" user "User.Comments")
		(21 "Eco1.User" user "User.Eco1")
		(23 "Eco2.User" user "User.Eco2")
		(25 "Edge.Cuts" user "Board Geometry/Outline")
		(27 "Margin" user)
		(31 "F.CrtYd" user "Package Geometry/Place Bound Top")
		(29 "B.CrtYd" user "Package Geometry/Place Bound Bottom")
		(35 "F.Fab" user "Ref Des/Assembly Top")
		(33 "B.Fab" user "Ref Des/Assembly Bottom")
	)
	(footprint ""
		(layer "F.Cu")
		(at 86.059518 -408.517344 -90)
		(property "Reference" "C684"
			(at 0 0 270)
			(layer "F.SilkS")
			(hide yes)
			(effects
				(font
					(size 1.27 1.27)
				)
			)
		)
		(property "Value" ""
			(at 0 0 270)
			(layer "F.Fab")
			(effects
				(font
					(size 1.27 1.27)
				)
			)
		)
		(duplicate_pad_numbers_are_jumpers no)
		(fp_line
			(start -0.299974 0.150114)
			(end -0.299974 -0.150114)
			(stroke
				(width 0.1)
				(type default)
			)
			(layer "F.Fab")
		)
		(fp_line
			(start 0.299974 0.150114)
			(end -0.299974 0.150114)
			(stroke
				(width 0.1)
				(type default)
			)
			(layer "F.Fab")
		)
		(fp_line
			(start -0.299974 -0.150114)
			(end 0.299974 -0.150114)
			(stroke
				(width 0.1)
				(type default)
			)
			(layer "F.Fab")
		)
		(fp_line
			(start 0.299974 -0.150114)
			(end 0.299974 0.150114)
			(stroke
				(width 0.1)
				(type default)
			)
			(layer "F.Fab")
		)
		(pad "1" smd rect
			(at -0.2667 0 270)
			(size 0.3048 0.381)
			(layers "F.Cu" "F.Mask" "F.Paste")
			(net "P5E_CPU1_PE4_TX_C_DN<12>")
		)
		(pad "2" smd rect
			(at 0.2667 0 270)
			(size 0.3048 0.381)
			(layers "F.Cu" "F.Mask" "F.Paste")
			(net "P5E_CPU1_PE4_TX_DN<12>")
		)
	)
	(footprint ""
		(layer "F.Cu")
		(at 164.251894 -34.164524)
		(property "Reference" "R4449"
			(at 0 0 0)
			(layer "F.SilkS")
			(hide yes)
			(effects
				(font
					(size 1.27 1.27)
				)
			)
		)
		(property "Value" ""
			(at 0 0 0)
			(layer "F.Fab")
			(effects
				(font
					(size 1.27 1.27)
				)
			)
		)
		(duplicate_pad_numbers_are_jumpers no)
		(fp_line
			(start -0.7874 -0.4064)
			(end 0.7874 -0.4064)
			(stroke
				(width 0.1524)
				(type default)
			)
			(layer "F.SilkS")
		)
		(fp_line
			(start -0.7874 0.4064)
			(end -0.7874 -0.4064)
			(stroke
				(width 0.1524)
				(type default)
			)
			(layer "F.SilkS")
		)
		(fp_line
			(start 0.7874 -0.4064)
			(end 0.7874 0.4064)
			(stroke
				(width 0.1524)
				(type default)
			)
			(layer "F.SilkS")
		)
		(fp_line
			(start 0.7874 0.4064)
			(end -0.7874 0.4064)
			(stroke
				(width 0.1524)
				(type default)
			)
			(layer "F.SilkS")
		)
		(fp_line
			(start -0.67945 -0.305054)
			(end -0.12065 -0.305054)
			(stroke
				(width 0.1)
				(type default)
			)
			(layer "F.Fab")
		)
		(fp_line
			(start -0.67945 0.3048)
			(end -0.67945 -0.305054)
			(stroke
				(width 0.1)
				(type default)
			)
			(layer "F.Fab")
		)
		(fp_line
			(start -0.12065 -0.305054)
			(end -0.12065 -0.2794)
			(stroke
				(width 0.1)
				(type default)
			)
			(layer "F.Fab")
		)
		(fp_line
			(start -0.12065 -0.2794)
			(end 0.12065 -0.2794)
			(stroke
				(width 0.1)
				(type default)
			)
			(layer "F.Fab")
		)
		(fp_line
			(start -0.12065 0.2794)
			(end -0.12065 0.3048)
			(stroke
				(width 0.1)
				(type default)
			)
			(layer "F.Fab")
		)
		(fp_line
			(start -0.12065 0.3048)
			(end -0.67945 0.3048)
			(stroke
				(width 0.1)
				(type default)
			)
			(layer "F.Fab")
		)
		(fp_line
			(start 0.120396 0.2794)
			(end -0.12065 0.2794)
			(stroke
				(width 0.1)
				(type default)
			)
			(layer "F.Fab")
		)
		(fp_line
			(start 0.120396 0.3048)
			(end 0.120396 0.2794)
			(stroke
				(width 0.1)
				(type default)
			)
			(layer "F.Fab")
		)
		(fp_line
			(start 0.12065 -0.3048)
			(end 0.67945 -0.3048)
			(stroke
				(width 0.1)
				(type default)
			)
			(layer "F.Fab")
		)
		(fp_line
			(start 0.12065 -0.2794)
			(end 0.12065 -0.3048)
			(stroke
				(width 0.1)
				(type default)
			)
			(layer "F.Fab")
		)
		(fp_line
			(start 0.67945 -0.3048)
			(end 0.67945 0.3048)
			(stroke
				(width 0.1)
				(type default)
			)
			(layer "F.Fab")
		)
		(fp_line
			(start 0.67945 0.3048)
			(end 0.120396 0.3048)
			(stroke
				(width 0.1)
				(type default)
			)
			(layer "F.Fab")
		)
		(pad "1" smd circle
			(at -0.40005 0)
			(size 0 0)
			(layers "F.Cu" "F.Mask" "F.Paste")
			(net "USB_HUB_2_PSELF")
		)
		(pad "2" smd circle
			(at 0.40005 0)
			(size 0 0)
			(layers "F.Cu" "F.Mask" "F.Paste")
			(net "GND")
		)
	)
	(footprint ""
		(layer "F.Cu")
		(at 454.847452 -21.302218 90)
		(property "Reference" "R3799"
			(at 0 0 90)
			(layer "F.SilkS")
			(hide yes)
			(effects
				(font
					(size 1.27 1.27)
				)
			)
		)
		(property "Value" ""
			(at 0 0 90)
			(layer "F.Fab")
			(effects
				(font
					(size 1.27 1.27)
				)
			)
		)
		(duplicate_pad_numbers_are_jumpers no)
		(fp_line
			(start 0.7874 -0.4064)
			(end 0.7874 0.4064)
			(stroke
				(width 0.1524)
				(type default)
			)
			(layer "F.SilkS")
		)
		(fp_line
			(start -0.7874 -0.4064)
			(end 0.7874 -0.4064)
			(stroke
				(width 0.1524)
				(type default)
			)
			(layer "F.SilkS")
		)
		(fp_line
			(start 0.7874 0.4064)
			(end -0.7874 0.4064)
			(stroke
				(width 0.1524)
				(type default)
			)
			(layer "F.SilkS")
		)
		(fp_line
			(start -0.7874 0.4064)
			(end -0.7874 -0.4064)
			(stroke
				(width 0.1524)
				(type default)
			)
			(layer "F.SilkS")
		)
		(fp_line
			(start -0.12065 -0.305054)
			(end -0.12065 -0.2794)
			(stroke
				(width 0.1)
				(type default)
			)
			(layer "F.Fab")
		)
		(fp_line
			(start -0.67945 -0.305054)
			(end -0.12065 -0.305054)
			(stroke
				(width 0.1)
				(type default)
			)
			(layer "F.Fab")
		)
		(fp_line
			(start 0.67945 -0.3048)
			(end 0.67945 0.3048)
			(stroke
				(width 0.1)
				(type default)
			)
			(layer "F.Fab")
		)
		(fp_line
			(start 0.12065 -0.3048)
			(end 0.67945 -0.3048)
			(stroke
				(width 0.1)
				(type default)
			)
			(layer "F.Fab")
		)
		(fp_line
			(start 0.12065 -0.2794)
			(end 0.12065 -0.3048)
			(stroke
				(width 0.1)
				(type default)
			)
			(layer "F.Fab")
		)
		(fp_line
			(start -0.12065 -0.2794)
			(end 0.12065 -0.2794)
			(stroke
				(width 0.1)
				(type default)
			)
			(layer "F.Fab")
		)
		(fp_line
			(start 0.120396 0.2794)
			(end -0.12065 0.2794)
			(stroke
				(width 0.1)
				(type default)
			)
			(layer "F.Fab")
		)
		(fp_line
			(start -0.12065 0.2794)
			(end -0.12065 0.3048)
			(stroke
				(width 0.1)
				(type default)
			)
			(layer "F.Fab")
		)
		(fp_line
			(start 0.67945 0.3048)
			(end 0.120396 0.3048)
			(stroke
				(width 0.1)
				(type default)
			)
			(layer "F.Fab")
		)
		(fp_line
			(start 0.120396 0.3048)
			(end 0.120396 0.2794)
			(stroke
				(width 0.1)
				(type default)
			)
			(layer "F.Fab")
		)
		(fp_line
			(start -0.12065 0.3048)
			(end -0.67945 0.3048)
			(stroke
				(width 0.1)
				(type default)
			)
			(layer "F.Fab")
		)
		(fp_line
			(start -0.67945 0.3048)
			(end -0.67945 -0.305054)
			(stroke
				(width 0.1)
				(type default)
			)
			(layer "F.Fab")
		)
		(pad "1" smd circle
			(at -0.40005 0 90)
			(size 0 0)
			(layers "F.Cu" "F.Mask" "F.Paste")
			(net "P3V3_AUX")
		)
		(pad "2" smd circle
			(at 0.40005 0 90)
			(size 0 0)
			(layers "F.Cu" "F.Mask" "F.Paste")
			(net "P12V_OCP_FAULT_1")
		)
	)
)
